(kicad_pcb
	(version 20260206)
	(generator "pcbnew")
	(generator_version "10.0")
	(general
		(thickness 1.6)
		(legacy_teardrops no)
	)
	(paper "A4")
	(title_block
		(title "fcb — 12433-1M.1206WZS1330.brd")
		(comment 1 "Open Vault / Knox (Wiwynn) / footprints 16-23 of 495")
	)
	(layers
		(0 "F.Cu" signal "TOP")
		(4 "In1.Cu" signal "L2GND")
		(6 "In2.Cu" signal "L3VCC")
		(2 "B.Cu" signal "BOTTOM")
		(9 "F.Adhes" user "F.Adhesive")
		(11 "B.Adhes" user "B.Adhesive")
		(13 "F.Paste" user "Package Geometry/Pastemask Top")
		(15 "B.Paste" user "Package Geometry/Pastemask Bottom")
		(5 "F.SilkS" user "Ref Des/Silkscreen Top")
		(7 "B.SilkS" user "Ref Des/Silkscreen Bottom")
		(1 "F.Mask" user "Board Geometry/Soldermask Top")
		(3 "B.Mask" user "Board Geometry/Soldermask Bottom")
		(17 "Dwgs.User" user "User.Drawings")
		(19 "Cmts.User" user "User.Comments")
		(21 "Eco1.User" user "User.Eco1")
		(23 "Eco2.User" user "User.Eco2")
		(25 "Edge.Cuts" user "Board Geometry/Outline")
		(27 "Margin" user)
		(31 "F.CrtYd" user "Package Geometry/Place Bound Top")
		(29 "B.CrtYd" user "Package Geometry/Place Bound Bottom")
		(35 "F.Fab" user "Ref Des/Assembly Top")
		(33 "B.Fab" user "Ref Des/Assembly Bottom")
	)
	(footprint ""
		(layer "F.Cu")
		(at 40.386 -370.332 -90)
		(property "Reference" "PR48"
			(at 0 0 270)
			(layer "F.SilkS")
			(hide yes)
			(effects
				(font
					(size 1.27 1.27)
				)
			)
		)
		(property "Value" "5K1R2F-2-GP"
			(at 0.064008 -3.993896 270)
			(unlocked yes)
			(layer "F.Fab")
			(hide yes)
			(effects
				(font
					(size 1.016 1.016)
					(thickness 0.1524)
				)
			)
		)
		(property "Device Type" "R402H16"
			(at 0.064008 -5.517896 270)
			(unlocked yes)
			(layer "F.Fab")
			(hide yes)
			(effects
				(font
					(size 1.016 1.016)
					(thickness 0.1524)
				)
			)
		)
		(duplicate_pad_numbers_are_jumpers no)
		(fp_line
			(start -0.508 -0.9398)
			(end -0.508 0.9398)
			(stroke
				(width 0.1524)
				(type default)
			)
			(layer "F.SilkS")
		)
		(fp_line
			(start 0.508 -0.9398)
			(end -0.508 -0.9398)
			(stroke
				(width 0.1524)
				(type default)
			)
			(layer "F.SilkS")
		)
		(fp_rect
			(start -0.508 0.9398)
			(end 0.508 -0.9398)
			(stroke
				(width 0)
				(type default)
			)
			(fill no)
			(layer "F.CrtYd")
		)
		(fp_rect
			(start -0.508 0.9398)
			(end 0.508 -0.9398)
			(stroke
				(width 0)
				(type default)
			)
			(fill no)
			(layer "F.Fab")
		)
		(pad "1" smd custom
			(at 0 -0.4445 270)
			(size 0.1397 0.1397)
			(layers "F.Cu" "F.Mask" "F.Paste")
			(net "ADM1276_EN_NET")
			(options
				(clearance outline)
				(anchor circle)
			)
			(primitives
				(gr_poly
					(pts
						(arc
							(start -0.1778 -0.2794)
							(mid -0.249642 -0.249642)
							(end -0.2794 -0.1778)
						)
						(arc
							(start -0.2794 0.1778)
							(mid -0.249642 0.249642)
							(end -0.1778 0.2794)
						)
						(arc
							(start 0.1778 0.2794)
							(mid 0.249642 0.249642)
							(end 0.2794 0.1778)
						)
						(arc
							(start 0.2794 -0.1778)
							(mid 0.249642 -0.249642)
							(end 0.1778 -0.2794)
						)
					)
					(width 0)
					(fill yes)
				)
			)
		)
		(pad "2" smd custom
			(at 0 0.4445 270)
			(size 0.1397 0.1397)
			(layers "F.Cu" "F.Mask" "F.Paste")
			(net "ADM1276_LATCH_B")
			(options
				(clearance outline)
				(anchor circle)
			)
			(primitives
				(gr_poly
					(pts
						(arc
							(start -0.1778 -0.2794)
							(mid -0.249642 -0.249642)
							(end -0.2794 -0.1778)
						)
						(arc
							(start -0.2794 0.1778)
							(mid -0.249642 0.249642)
							(end -0.1778 0.2794)
						)
						(arc
							(start 0.1778 0.2794)
							(mid 0.249642 0.249642)
							(end 0.2794 0.1778)
						)
						(arc
							(start 0.2794 -0.1778)
							(mid 0.249642 -0.249642)
							(end 0.1778 -0.2794)
						)
					)
					(width 0)
					(fill yes)
				)
			)
		)
	)
	(footprint ""
		(layer "F.Cu")
		(at 18.237708 -13.905738)
		(property "Reference" "C29"
			(at 0 0 0)
			(layer "F.SilkS")
			(hide yes)
			(effects
				(font
					(size 1.27 1.27)
				)
			)
		)
		(property "Value" "SCD1U16V2KX-3GP"
			(at 1.1811 -2.7051 0)
			(unlocked yes)
			(layer "F.Fab")
			(hide yes)
			(effects
				(font
					(size 1.016 1.016)
					(thickness 0.1524)
				)
			)
		)
		(property "Device Type" "C402H22"
			(at 1.1811 -4.2291 0)
			(unlocked yes)
			(layer "F.Fab")
			(hide yes)
			(effects
				(font
					(size 1.016 1.016)
					(thickness 0.1524)
				)
			)
		)
		(duplicate_pad_numbers_are_jumpers no)
		(fp_rect
			(start -0.4318 0.9525)
			(end 0.4318 -0.9525)
			(stroke
				(width 0)
				(type default)
			)
			(fill no)
			(layer "F.CrtYd")
		)
		(fp_rect
			(start -0.4318 0.9525)
			(end 0.4318 -0.9525)
			(stroke
				(width 0)
				(type default)
			)
			(fill no)
			(layer "F.Fab")
		)
		(pad "1" smd custom
			(at 0 -0.4445)
			(size 0.1524 0.1524)
			(layers "F.Cu" "F.Mask" "F.Paste")
			(net "FAN_TACH11")
			(options
				(clearance outline)
				(anchor circle)
			)
			(primitives
				(gr_poly
					(pts
						(arc
							(start 0.3048 -0.2032)
							(mid 0.275042 -0.275042)
							(end 0.2032 -0.3048)
						)
						(arc
							(start -0.2032 -0.3048)
							(mid -0.275042 -0.275042)
							(end -0.3048 -0.2032)
						)
						(arc
							(start -0.3048 0.2032)
							(mid -0.275042 0.275042)
							(end -0.2032 0.3048)
						)
						(arc
							(start 0.2032 0.3048)
							(mid 0.275042 0.275042)
							(end 0.3048 0.2032)
						)
					)
					(width 0)
					(fill yes)
				)
			)
		)
		(pad "2" smd custom
			(at 0 0.4445)
			(size 0.1524 0.1524)
			(layers "F.Cu" "F.Mask" "F.Paste")
			(net "GND")
			(options
				(clearance outline)
				(anchor circle)
			)
			(primitives
				(gr_poly
					(pts
						(arc
							(start 0.3048 -0.2032)
							(mid 0.275042 -0.275042)
							(end 0.2032 -0.3048)
						)
						(arc
							(start -0.2032 -0.3048)
							(mid -0.275042 -0.275042)
							(end -0.3048 -0.2032)
						)
						(arc
							(start -0.3048 0.2032)
							(mid -0.275042 0.275042)
							(end -0.2032 0.3048)
						)
						(arc
							(start 0.2032 0.3048)
							(mid 0.275042 0.275042)
							(end 0.3048 0.2032)
						)
					)
					(width 0)
					(fill yes)
				)
			)
		)
	)
	(footprint ""
		(layer "F.Cu")
		(at 23.749 -375.285 180)
		(property "Reference" "PR37"
			(at 0 0 180)
			(layer "F.SilkS")
			(hide yes)
			(effects
				(font
					(size 1.27 1.27)
				)
			)
		)
		(property "Value" "4K99R2F-L-GP"
			(at 0.064008 -3.993896 180)
			(unlocked yes)
			(layer "F.Fab")
			(hide yes)
			(effects
				(font
					(size 1.016 1.016)
					(thickness 0.1524)
				)
			)
		)
		(property "Device Type" "R402H16"
			(at 0.064008 -5.517896 180)
			(unlocked yes)
			(layer "F.Fab")
			(hide yes)
			(effects
				(font
					(size 1.016 1.016)
					(thickness 0.1524)
				)
			)
		)
		(duplicate_pad_numbers_are_jumpers no)
		(fp_line
			(start 0.508 -0.9398)
			(end -0.508 -0.9398)
			(stroke
				(width 0.1524)
				(type default)
			)
			(layer "F.SilkS")
		)
		(fp_line
			(start -0.508 -0.9398)
			(end -0.508 0.9398)
			(stroke
				(width 0.1524)
				(type default)
			)
			(layer "F.SilkS")
		)
		(fp_rect
			(start -0.508 0.9398)
			(end 0.508 -0.9398)
			(stroke
				(width 0)
				(type default)
			)
			(fill no)
			(layer "F.CrtYd")
		)
		(fp_rect
			(start -0.508 0.9398)
			(end 0.508 -0.9398)
			(stroke
				(width 0)
				(type default)
			)
			(fill no)
			(layer "F.Fab")
		)
		(pad "1" smd custom
			(at 0 -0.4445 180)
			(size 0.1397 0.1397)
			(layers "F.Cu" "F.Mask" "F.Paste")
			(net "ADM1276_UV")
			(options
				(clearance outline)
				(anchor circle)
			)
			(primitives
				(gr_poly
					(pts
						(arc
							(start -0.1778 -0.2794)
							(mid -0.249642 -0.249642)
							(end -0.2794 -0.1778)
						)
						(arc
							(start -0.2794 0.1778)
							(mid -0.249642 0.249642)
							(end -0.1778 0.2794)
						)
						(arc
							(start 0.1778 0.2794)
							(mid 0.249642 0.249642)
							(end 0.2794 0.1778)
						)
						(arc
							(start 0.2794 -0.1778)
							(mid 0.249642 -0.249642)
							(end 0.1778 -0.2794)
						)
					)
					(width 0)
					(fill yes)
				)
			)
		)
		(pad "2" smd custom
			(at 0 0.4445 180)
			(size 0.1397 0.1397)
			(layers "F.Cu" "F.Mask" "F.Paste")
			(net "GND")
			(options
				(clearance outline)
				(anchor circle)
			)
			(primitives
				(gr_poly
					(pts
						(arc
							(start -0.1778 -0.2794)
							(mid -0.249642 -0.249642)
							(end -0.2794 -0.1778)
						)
						(arc
							(start -0.2794 0.1778)
							(mid -0.249642 0.249642)
							(end -0.1778 0.2794)
						)
						(arc
							(start 0.1778 0.2794)
							(mid 0.249642 0.249642)
							(end 0.2794 0.1778)
						)
						(arc
							(start 0.2794 -0.1778)
							(mid 0.249642 -0.249642)
							(end 0.1778 -0.2794)
						)
					)
					(width 0)
					(fill yes)
				)
			)
		)
	)
	(footprint ""
		(layer "F.Cu")
		(at 40.2844 -366.319816)
		(property "Reference" "D18"
			(at 0 0 0)
			(layer "F.SilkS")
			(hide yes)
			(effects
				(font
					(size 1.27 1.27)
				)
			)
		)
		(property "Value" "CH751H-40PT-1GP"
			(at -0.1016 -4.4958 0)
			(unlocked yes)
			(layer "F.Fab")
			(hide yes)
			(effects
				(font
					(size 1.016 1.016)
					(thickness 0.1524)
				)
			)
		)
		(property "Device Type" "SOD80CAKH36"
			(at -0.1016 -6.0198 0)
			(unlocked yes)
			(layer "F.Fab")
			(hide yes)
			(effects
				(font
					(size 1.016 1.016)
					(thickness 0.1524)
				)
			)
		)
		(duplicate_pad_numbers_are_jumpers no)
		(fp_line
			(start -0.8128 -1.8796)
			(end -0.8128 1.8796)
			(stroke
				(width 0.1524)
				(type default)
			)
			(layer "F.SilkS")
		)
		(fp_line
			(start -0.8128 1.8796)
			(end 0.8128 1.8796)
			(stroke
				(width 0.1524)
				(type default)
			)
			(layer "F.SilkS")
		)
		(fp_line
			(start -0.6858 2.0066)
			(end 0.6858 2.0066)
			(stroke
				(width 0.4064)
				(type default)
			)
			(layer "F.SilkS")
		)
		(fp_line
			(start 0.8128 -1.8796)
			(end -0.8128 -1.8796)
			(stroke
				(width 0.1524)
				(type default)
			)
			(layer "F.SilkS")
		)
		(fp_line
			(start 0.8128 1.8796)
			(end 0.8128 -1.8796)
			(stroke
				(width 0.1524)
				(type default)
			)
			(layer "F.SilkS")
		)
		(fp_rect
			(start -0.889 2.2098)
			(end 0.889 -1.9558)
			(stroke
				(width 0)
				(type default)
			)
			(fill no)
			(layer "F.CrtYd")
		)
		(fp_rect
			(start -0.889 2.2098)
			(end 0.889 -1.9558)
			(stroke
				(width 0)
				(type default)
			)
			(fill no)
			(layer "F.Fab")
		)
		(pad "A" smd rect
			(at 0 -1.0668)
			(size 0.762 1.1684)
			(layers "F.Cu" "F.Mask" "F.Paste")
			(net "TEMP_ALM#_REVERSE")
		)
		(pad "K" smd rect
			(at 0 1.0668)
			(size 0.762 1.1684)
			(layers "F.Cu" "F.Mask" "F.Paste")
			(net "TEMP_ALM#_REVERSE_R")
		)
	)
	(footprint ""
		(layer "F.Cu")
		(at 39.5224 -134.7978)
		(property "Reference" "PR97"
			(at 0 0 0)
			(layer "F.SilkS")
			(hide yes)
			(effects
				(font
					(size 1.27 1.27)
				)
			)
		)
		(property "Value" "0R2J-2-GP"
			(at 0.064008 -3.993896 0)
			(unlocked yes)
			(layer "F.Fab")
			(hide yes)
			(effects
				(font
					(size 1.016 1.016)
					(thickness 0.1524)
				)
			)
		)
		(property "Device Type" "R402H16"
			(at 0.064008 -5.517896 0)
			(unlocked yes)
			(layer "F.Fab")
			(hide yes)
			(effects
				(font
					(size 1.016 1.016)
					(thickness 0.1524)
				)
			)
		)
		(duplicate_pad_numbers_are_jumpers no)
		(fp_line
			(start -0.508 -0.9398)
			(end -0.508 0.9398)
			(stroke
				(width 0.1524)
				(type default)
			)
			(layer "F.SilkS")
		)
		(fp_line
			(start 0.508 -0.9398)
			(end -0.508 -0.9398)
			(stroke
				(width 0.1524)
				(type default)
			)
			(layer "F.SilkS")
		)
		(fp_rect
			(start -0.508 0.9398)
			(end 0.508 -0.9398)
			(stroke
				(width 0)
				(type default)
			)
			(fill no)
			(layer "F.CrtYd")
		)
		(fp_rect
			(start -0.508 0.9398)
			(end 0.508 -0.9398)
			(stroke
				(width 0)
				(type default)
			)
			(fill no)
			(layer "F.Fab")
		)
		(pad "1" smd custom
			(at 0 -0.4445)
			(size 0.1397 0.1397)
			(layers "F.Cu" "F.Mask" "F.Paste")
			(net "P12VL_2490_SENSE")
			(options
				(clearance outline)
				(anchor circle)
			)
			(primitives
				(gr_poly
					(pts
						(arc
							(start -0.1778 -0.2794)
							(mid -0.249642 -0.249642)
							(end -0.2794 -0.1778)
						)
						(arc
							(start -0.2794 0.1778)
							(mid -0.249642 0.249642)
							(end -0.1778 0.2794)
						)
						(arc
							(start 0.1778 0.2794)
							(mid 0.249642 0.249642)
							(end 0.2794 0.1778)
						)
						(arc
							(start 0.2794 -0.1778)
							(mid 0.249642 -0.249642)
							(end 0.1778 -0.2794)
						)
					)
					(width 0)
					(fill yes)
				)
			)
		)
		(pad "2" smd custom
			(at 0 0.4445)
			(size 0.1397 0.1397)
			(layers "F.Cu" "F.Mask" "F.Paste")
			(net "P12VL_NET")
			(options
				(clearance outline)
				(anchor circle)
			)
			(primitives
				(gr_poly
					(pts
						(arc
							(start -0.1778 -0.2794)
							(mid -0.249642 -0.249642)
							(end -0.2794 -0.1778)
						)
						(arc
							(start -0.2794 0.1778)
							(mid -0.249642 0.249642)
							(end -0.1778 0.2794)
						)
						(arc
							(start 0.1778 0.2794)
							(mid 0.249642 0.249642)
							(end 0.2794 0.1778)
						)
						(arc
							(start 0.2794 -0.1778)
							(mid 0.249642 -0.249642)
							(end 0.1778 -0.2794)
						)
					)
					(width 0)
					(fill yes)
				)
			)
		)
	)
	(footprint ""
		(layer "F.Cu")
		(at 21.7678 -219.8878 90)
		(property "Reference" "R135"
			(at 0 0 90)
			(layer "F.SilkS")
			(hide yes)
			(effects
				(font
					(size 1.27 1.27)
				)
			)
		)
		(property "Value" "4K7R2F-GP"
			(at 0.064008 -3.993896 90)
			(unlocked yes)
			(layer "F.Fab")
			(hide yes)
			(effects
				(font
					(size 1.016 1.016)
					(thickness 0.1524)
				)
			)
		)
		(property "Device Type" "R402H16"
			(at 0.064008 -5.517896 90)
			(unlocked yes)
			(layer "F.Fab")
			(hide yes)
			(effects
				(font
					(size 1.016 1.016)
					(thickness 0.1524)
				)
			)
		)
		(duplicate_pad_numbers_are_jumpers no)
		(fp_line
			(start 0.508 -0.9398)
			(end -0.508 -0.9398)
			(stroke
				(width 0.1524)
				(type default)
			)
			(layer "F.SilkS")
		)
		(fp_line
			(start -0.508 -0.9398)
			(end -0.508 0.9398)
			(stroke
				(width 0.1524)
				(type default)
			)
			(layer "F.SilkS")
		)
		(fp_rect
			(start -0.508 0.9398)
			(end 0.508 -0.9398)
			(stroke
				(width 0)
				(type default)
			)
			(fill no)
			(layer "F.CrtYd")
		)
		(fp_rect
			(start -0.508 0.9398)
			(end 0.508 -0.9398)
			(stroke
				(width 0)
				(type default)
			)
			(fill no)
			(layer "F.Fab")
		)
		(pad "1" smd custom
			(at 0 -0.4445 90)
			(size 0.1397 0.1397)
			(layers "F.Cu" "F.Mask" "F.Paste")
			(net "P3V3")
			(options
				(clearance outline)
				(anchor circle)
			)
			(primitives
				(gr_poly
					(pts
						(arc
							(start -0.1778 -0.2794)
							(mid -0.249642 -0.249642)
							(end -0.2794 -0.1778)
						)
						(arc
							(start -0.2794 0.1778)
							(mid -0.249642 0.249642)
							(end -0.1778 0.2794)
						)
						(arc
							(start 0.1778 0.2794)
							(mid 0.249642 0.249642)
							(end 0.2794 0.1778)
						)
						(arc
							(start 0.2794 -0.1778)
							(mid 0.249642 -0.249642)
							(end 0.1778 -0.2794)
						)
					)
					(width 0)
					(fill yes)
				)
			)
		)
		(pad "2" smd custom
			(at 0 0.4445 90)
			(size 0.1397 0.1397)
			(layers "F.Cu" "F.Mask" "F.Paste")
			(net "PWM_OUT_FAN1")
			(options
				(clearance outline)
				(anchor circle)
			)
			(primitives
				(gr_poly
					(pts
						(arc
							(start -0.1778 -0.2794)
							(mid -0.249642 -0.249642)
							(end -0.2794 -0.1778)
						)
						(arc
							(start -0.2794 0.1778)
							(mid -0.249642 0.249642)
							(end -0.1778 0.2794)
						)
						(arc
							(start 0.1778 0.2794)
							(mid 0.249642 0.249642)
							(end 0.2794 0.1778)
						)
						(arc
							(start 0.2794 -0.1778)
							(mid 0.249642 -0.249642)
							(end 0.1778 -0.2794)
						)
					)
					(width 0)
					(fill yes)
				)
			)
		)
	)
	(footprint ""
		(layer "F.Cu")
		(at 5.1054 -437.0578 90)
		(property "Reference" "R121"
			(at 0 0 90)
			(layer "F.SilkS")
			(hide yes)
			(effects
				(font
					(size 1.27 1.27)
				)
			)
		)
		(property "Value" "2KR2F-3-GP"
			(at 0.064008 -3.993896 90)
			(unlocked yes)
			(layer "F.Fab")
			(hide yes)
			(effects
				(font
					(size 1.016 1.016)
					(thickness 0.1524)
				)
			)
		)
		(property "Device Type" "R402H16"
			(at 0.064008 -5.517896 90)
			(unlocked yes)
			(layer "F.Fab")
			(hide yes)
			(effects
				(font
					(size 1.016 1.016)
					(thickness 0.1524)
				)
			)
		)
		(duplicate_pad_numbers_are_jumpers no)
		(fp_line
			(start 0.508 -0.9398)
			(end -0.508 -0.9398)
			(stroke
				(width 0.1524)
				(type default)
			)
			(layer "F.SilkS")
		)
		(fp_line
			(start -0.508 -0.9398)
			(end -0.508 0.9398)
			(stroke
				(width 0.1524)
				(type default)
			)
			(layer "F.SilkS")
		)
		(fp_rect
			(start -0.508 0.9398)
			(end 0.508 -0.9398)
			(stroke
				(width 0)
				(type default)
			)
			(fill no)
			(layer "F.CrtYd")
		)
		(fp_rect
			(start -0.508 0.9398)
			(end 0.508 -0.9398)
			(stroke
				(width 0)
				(type default)
			)
			(fill no)
			(layer "F.Fab")
		)
		(pad "1" smd custom
			(at 0 -0.4445 90)
			(size 0.1397 0.1397)
			(layers "F.Cu" "F.Mask" "F.Paste")
			(net "LED_DR_LED0")
			(options
				(clearance outline)
				(anchor circle)
			)
			(primitives
				(gr_poly
					(pts
						(arc
							(start -0.1778 -0.2794)
							(mid -0.249642 -0.249642)
							(end -0.2794 -0.1778)
						)
						(arc
							(start -0.2794 0.1778)
							(mid -0.249642 0.249642)
							(end -0.1778 0.2794)
						)
						(arc
							(start 0.1778 0.2794)
							(mid 0.249642 0.249642)
							(end 0.2794 0.1778)
						)
						(arc
							(start 0.2794 -0.1778)
							(mid 0.249642 -0.249642)
							(end 0.1778 -0.2794)
						)
					)
					(width 0)
					(fill yes)
				)
			)
		)
		(pad "2" smd custom
			(at 0 0.4445 90)
			(size 0.1397 0.1397)
			(layers "F.Cu" "F.Mask" "F.Paste")
			(net "LED_DR_LED0_B")
			(options
				(clearance outline)
				(anchor circle)
			)
			(primitives
				(gr_poly
					(pts
						(arc
							(start -0.1778 -0.2794)
							(mid -0.249642 -0.249642)
							(end -0.2794 -0.1778)
						)
						(arc
							(start -0.2794 0.1778)
							(mid -0.249642 0.249642)
							(end -0.1778 0.2794)
						)
						(arc
							(start 0.1778 0.2794)
							(mid 0.249642 0.249642)
							(end 0.2794 0.1778)
						)
						(arc
							(start 0.2794 -0.1778)
							(mid 0.249642 -0.249642)
							(end 0.1778 -0.2794)
						)
					)
					(width 0)
					(fill yes)
				)
			)
		)
	)
	(footprint ""
		(layer "F.Cu")
		(at 25.8826 -166.1414 180)
		(property "Reference" "TP5"
			(at 0 0 180)
			(layer "F.SilkS")
			(hide yes)
			(effects
				(font
					(size 1.27 1.27)
				)
			)
		)
		(property "Value" "TPAD32-GP"
			(at 0 -3.166364 180)
			(unlocked yes)
			(layer "F.Fab")
			(hide yes)
			(effects
				(font
					(size 1.016 1.016)
					(thickness 0.1524)
				)
			)
		)
		(property "Device Type" "TPAD32"
			(at 0 -4.690618 180)
			(unlocked yes)
			(layer "F.Fab")
			(hide yes)
			(effects
				(font
					(size 1.016 1.016)
					(thickness 0.1524)
				)
			)
		)
		(duplicate_pad_numbers_are_jumpers no)
		(fp_poly
			(pts
				(arc
					(start -0.7112 0)
					(mid 0.7112 0)
					(end -0.7112 0)
				)
			)
			(stroke
				(width 0)
				(type default)
			)
			(fill no)
			(layer "F.CrtYd")
		)
		(fp_poly
			(pts
				(arc
					(start -0.7112 0)
					(mid 0.7112 0)
					(end -0.7112 0)
				)
			)
			(stroke
				(width 0)
				(type default)
			)
			(fill no)
			(layer "F.Fab")
		)
		(pad "1" smd circle
			(at 0 0 180)
			(size 0.8128 0.8128)
			(layers "F.Cu" "F.Mask" "F.Paste")
			(net "NCT7904D_PWM4")
		)
	)
)
